#ISCELL
  pure_quanta quanta_title_block_c *
  *
#ISCELL
  standard offpage *
  page421_i1
#CELL
  pure_quanta q_res *
  page421_i18
#ISCELL
  pure_quanta_power universal_gnd *
  page421_i19
#ISCELL
  standard offpage *
  page421_i2
#ISCELL
  pure_quanta_power universal_gnd *
  page421_i20
#ISCELL
  pure_quanta_power universal_gnd *
  page421_i21
#ISCELL
  pure_quanta_power p1v0 *
  page421_i22
#CELL
  pure_quanta q_cap *
  page421_i23
#ISCELL
  pure_quanta_power universal_gnd *
  page421_i24
#CELL
  pure_quanta q_res *
  page421_i3
#CELL
  pure_quanta q_res *
  page421_i4
#CELL
  pure_quanta m24m02drmn6tp *
  page421_i5
